(kicad_pcb
	(version 20260206)
	(generator "pcbnew")
	(generator_version "10.0")
	(general
		(thickness 1.6)
		(legacy_teardrops no)
	)
	(paper "A4")
	(title_block
		(title "Wiwynn_Tioga_Pass_MB.brd")
		(comment 1 "Tioga Pass / footprints 4003-4009 of 4770")
	)
	(layers
		(0 "F.Cu" signal "TOP")
		(4 "In1.Cu" signal "L2GND")
		(6 "In2.Cu" signal "L3")
		(8 "In3.Cu" signal "L4GND")
		(10 "In4.Cu" signal "L5")
		(12 "In5.Cu" signal "L6GND")
		(14 "In6.Cu" signal "L7VCC")
		(16 "In7.Cu" signal "L8VCC")
		(18 "In8.Cu" signal "L9GND")
		(20 "In9.Cu" signal "L10")
		(22 "In10.Cu" signal "L11GND")
		(24 "In11.Cu" signal "L12")
		(26 "In12.Cu" signal "L13GND")
		(2 "B.Cu" signal "BOTTOM")
		(9 "F.Adhes" user "F.Adhesive")
		(11 "B.Adhes" user "B.Adhesive")
		(13 "F.Paste" user "Package Geometry/Pastemask Top")
		(15 "B.Paste" user "Package Geometry/Pastemask Bottom")
		(5 "F.SilkS" user "Ref Des/Silkscreen Top")
		(7 "B.SilkS" user "Ref Des/Silkscreen Bottom")
		(1 "F.Mask" user "Board Geometry/Soldermask Top")
		(3 "B.Mask" user "Board Geometry/Soldermask Bottom")
		(17 "Dwgs.User" user "User.Drawings")
		(19 "Cmts.User" user "User.Comments")
		(21 "Eco1.User" user "User.Eco1")
		(23 "Eco2.User" user "User.Eco2")
		(25 "Edge.Cuts" user "Board Geometry/Outline")
		(27 "Margin" user)
		(31 "F.CrtYd" user "Package Geometry/Place Bound Top")
		(29 "B.CrtYd" user "Package Geometry/Place Bound Bottom")
		(35 "F.Fab" user "Ref Des/Assembly Top")
		(33 "B.Fab" user "Ref Des/Assembly Bottom")
	)
	(footprint ""
		(layer "B.Cu")
		(at 420.116 -32.512 90)
		(property "Reference" "C25W22"
			(at 0.8382 -0.67818 90)
			(unlocked yes)
			(layer "B.SilkS")
			(effects
				(font
					(size 0.4064 0.254)
					(thickness 0.1524)
				)
				(justify left mirror)
			)
		)
		(property "Value" ""
			(at 0 0 90)
			(layer "B.Fab")
			(effects
				(font
					(size 1.27 1.27)
				)
				(justify mirror)
			)
		)
		(duplicate_pad_numbers_are_jumpers no)
		(fp_poly
			(pts
				(xy -0.3048 -0.1016) (xy -0.3048 0.9906) (xy 0.3048 0.9906) (xy 0.3048 -0.1016)
			)
			(stroke
				(width 0)
				(type default)
			)
			(fill no)
			(layer "B.CrtYd")
		)
		(fp_line
			(start 0.3048 -0.1016)
			(end 0.3048 0.9906)
			(stroke
				(width 0.1)
				(type default)
			)
			(layer "B.Fab")
		)
		(fp_line
			(start -0.3048 -0.1016)
			(end 0.3048 -0.1016)
			(stroke
				(width 0.1)
				(type default)
			)
			(layer "B.Fab")
		)
		(fp_line
			(start 0.3048 0.9906)
			(end -0.3048 0.9906)
			(stroke
				(width 0.1)
				(type default)
			)
			(layer "B.Fab")
		)
		(fp_line
			(start -0.3048 0.9906)
			(end -0.3048 -0.1016)
			(stroke
				(width 0.1)
				(type default)
			)
			(layer "B.Fab")
		)
		(pad "1" smd rect
			(at 0 0 270)
			(size 0.508 0.508)
			(layers "B.Cu" "B.Mask" "B.Paste")
			(net "BMC_M_VREFCA")
		)
		(pad "2" smd rect
			(at 0 0.889 270)
			(size 0.508 0.508)
			(layers "B.Cu" "B.Mask" "B.Paste")
			(net "GND")
		)
		(zone
			(layer "B.Cu")
			(hatch none 0.5)
			(connect_pads
				(clearance 0)
			)
			(min_thickness 0.25)
			(keepout
				(tracks allowed)
				(vias not_allowed)
				(pads allowed)
				(copperpour not_allowed)
				(footprints allowed)
			)
			(placement
				(enabled no)
				(sheetname "")
			)
			(fill
				(thermal_gap 0.5)
				(thermal_bridge_width 0.5)
				(island_removal_mode 0)
			)
			(polygon
				(pts
					(xy 420.37 -32.766) (xy 420.37 -32.258) (xy 420.751 -32.258) (xy 420.751 -32.766)
				)
			)
		)
		(zone
			(layer "B.Cu")
			(hatch none 0.5)
			(connect_pads
				(clearance 0)
			)
			(min_thickness 0.25)
			(keepout
				(tracks not_allowed)
				(vias allowed)
				(pads allowed)
				(copperpour not_allowed)
				(footprints allowed)
			)
			(placement
				(enabled no)
				(sheetname "")
			)
			(fill
				(thermal_gap 0.5)
				(thermal_bridge_width 0.5)
				(island_removal_mode 0)
			)
			(polygon
				(pts
					(xy 420.751 -32.766) (xy 420.751 -32.258) (xy 420.37 -32.258) (xy 420.37 -32.766)
				)
			)
		)
	)
	(footprint ""
		(layer "B.Cu")
		(at 481.6475 -46.5582 -90)
		(property "Reference" "R1R15"
			(at 0 0 90)
			(layer "B.SilkS")
			(hide yes)
			(effects
				(font
					(size 1.27 1.27)
				)
				(justify mirror)
			)
		)
		(property "Value" ""
			(at 0 0 90)
			(layer "B.Fab")
			(effects
				(font
					(size 1.27 1.27)
				)
				(justify mirror)
			)
		)
		(duplicate_pad_numbers_are_jumpers no)
		(fp_poly
			(pts
				(xy 0.4953 -0.2032) (xy -0.4953 -0.2032) (xy -0.4953 1.6002) (xy 0.4953 1.6002)
			)
			(stroke
				(width 0)
				(type default)
			)
			(fill no)
			(layer "B.CrtYd")
		)
		(fp_line
			(start -0.4953 1.6002)
			(end 0.4953 1.6002)
			(stroke
				(width 0.1)
				(type default)
			)
			(layer "B.Fab")
		)
		(fp_line
			(start 0.4953 1.6002)
			(end 0.4953 -0.2032)
			(stroke
				(width 0.1)
				(type default)
			)
			(layer "B.Fab")
		)
		(fp_line
			(start -0.4953 -0.2032)
			(end -0.4953 1.6002)
			(stroke
				(width 0.1)
				(type default)
			)
			(layer "B.Fab")
		)
		(fp_line
			(start 0.4953 -0.2032)
			(end -0.4953 -0.2032)
			(stroke
				(width 0.1)
				(type default)
			)
			(layer "B.Fab")
		)
		(pad "1" smd rect
			(at 0 0 90)
			(size 0.762 0.889)
			(layers "B.Cu" "B.Mask" "B.Paste")
			(net "P0V9_LAN")
		)
		(pad "2" smd rect
			(at 0 1.397 90)
			(size 0.762 0.889)
			(layers "B.Cu" "B.Mask" "B.Paste")
			(net "P0V9_LAN_I210")
		)
		(zone
			(layer "B.Cu")
			(hatch none 0.5)
			(connect_pads
				(clearance 0)
			)
			(min_thickness 0.25)
			(keepout
				(tracks allowed)
				(vias not_allowed)
				(pads allowed)
				(copperpour not_allowed)
				(footprints allowed)
			)
			(placement
				(enabled no)
				(sheetname "")
			)
			(fill
				(thermal_gap 0.5)
				(thermal_bridge_width 0.5)
				(island_removal_mode 0)
			)
			(polygon
				(pts
					(xy 480.695 -46.9392) (xy 481.203 -46.9392) (xy 481.203 -46.1772) (xy 480.695 -46.1772)
				)
			)
		)
		(zone
			(layer "B.Cu")
			(hatch none 0.5)
			(connect_pads
				(clearance 0)
			)
			(min_thickness 0.25)
			(keepout
				(tracks not_allowed)
				(vias allowed)
				(pads allowed)
				(copperpour not_allowed)
				(footprints allowed)
			)
			(placement
				(enabled no)
				(sheetname "")
			)
			(fill
				(thermal_gap 0.5)
				(thermal_bridge_width 0.5)
				(island_removal_mode 0)
			)
			(polygon
				(pts
					(xy 480.695 -46.1772) (xy 481.203 -46.1772) (xy 481.203 -46.9392) (xy 480.695 -46.9392)
				)
			)
		)
	)
	(footprint ""
		(layer "B.Cu")
		(at 345.919806 -60.368434)
		(property "Reference" "R2U23"
			(at 0 0 0)
			(layer "B.SilkS")
			(hide yes)
			(effects
				(font
					(size 1.27 1.27)
				)
				(justify mirror)
			)
		)
		(property "Value" ""
			(at 0 0 0)
			(layer "B.Fab")
			(effects
				(font
					(size 1.27 1.27)
				)
				(justify mirror)
			)
		)
		(duplicate_pad_numbers_are_jumpers no)
		(fp_poly
			(pts
				(xy 0.2794 -0.1016) (xy -0.2794 -0.1016) (xy -0.2794 0.9906) (xy 0.2794 0.9906)
			)
			(stroke
				(width 0)
				(type default)
			)
			(fill no)
			(layer "B.CrtYd")
		)
		(fp_line
			(start -0.2794 -0.1016)
			(end 0.2794 -0.1016)
			(stroke
				(width 0.1)
				(type default)
			)
			(layer "B.Fab")
		)
		(fp_line
			(start -0.2794 0.9906)
			(end -0.2794 -0.1016)
			(stroke
				(width 0.1)
				(type default)
			)
			(layer "B.Fab")
		)
		(fp_line
			(start 0.2794 -0.1016)
			(end 0.2794 0.9906)
			(stroke
				(width 0.1)
				(type default)
			)
			(layer "B.Fab")
		)
		(fp_line
			(start 0.2794 0.9906)
			(end -0.2794 0.9906)
			(stroke
				(width 0.1)
				(type default)
			)
			(layer "B.Fab")
		)
		(pad "1" smd rect
			(at 0 0 180)
			(size 0.508 0.508)
			(layers "B.Cu" "B.Mask" "B.Paste")
			(net "P3E_CPU0_PE1_SS_RXN<4>")
		)
		(pad "2" smd rect
			(at 0 0.889 180)
			(size 0.508 0.508)
			(layers "B.Cu" "B.Mask" "B.Paste")
			(net "P3E_CPU0_PE1_SS_R_RXN<4>")
		)
		(zone
			(layer "B.Cu")
			(hatch none 0.5)
			(connect_pads
				(clearance 0)
			)
			(min_thickness 0.25)
			(keepout
				(tracks allowed)
				(vias not_allowed)
				(pads allowed)
				(copperpour not_allowed)
				(footprints allowed)
			)
			(placement
				(enabled no)
				(sheetname "")
			)
			(fill
				(thermal_gap 0.5)
				(thermal_bridge_width 0.5)
				(island_removal_mode 0)
			)
			(polygon
				(pts
					(xy 346.173806 -60.114434) (xy 345.665806 -60.114434) (xy 345.665806 -59.733434) (xy 346.173806 -59.733434)
				)
			)
		)
	)
	(footprint ""
		(layer "B.Cu")
		(at 468.884 -125.984 180)
		(property "Reference" "R1W13"
			(at 0.8382 -0.67818 180)
			(unlocked yes)
			(layer "B.SilkS")
			(effects
				(font
					(size 0.4064 0.254)
					(thickness 0.1524)
				)
				(justify left mirror)
			)
		)
		(property "Value" ""
			(at 0 0 0)
			(layer "B.Fab")
			(effects
				(font
					(size 1.27 1.27)
				)
				(justify mirror)
			)
		)
		(duplicate_pad_numbers_are_jumpers no)
		(fp_poly
			(pts
				(xy 0.2794 -0.1016) (xy -0.2794 -0.1016) (xy -0.2794 0.9906) (xy 0.2794 0.9906)
			)
			(stroke
				(width 0)
				(type default)
			)
			(fill no)
			(layer "B.CrtYd")
		)
		(fp_line
			(start 0.2794 0.9906)
			(end -0.2794 0.9906)
			(stroke
				(width 0.1)
				(type default)
			)
			(layer "B.Fab")
		)
		(fp_line
			(start 0.2794 -0.1016)
			(end 0.2794 0.9906)
			(stroke
				(width 0.1)
				(type default)
			)
			(layer "B.Fab")
		)
		(fp_line
			(start -0.2794 0.9906)
			(end -0.2794 -0.1016)
			(stroke
				(width 0.1)
				(type default)
			)
			(layer "B.Fab")
		)
		(fp_line
			(start -0.2794 -0.1016)
			(end 0.2794 -0.1016)
			(stroke
				(width 0.1)
				(type default)
			)
			(layer "B.Fab")
		)
		(pad "1" smd rect
			(at 0 0)
			(size 0.508 0.508)
			(layers "B.Cu" "B.Mask" "B.Paste")
			(net "FM_USB_P0_EN_BOOT_BIOS_STRAP_N")
		)
		(pad "2" smd rect
			(at 0 0.889)
			(size 0.508 0.508)
			(layers "B.Cu" "B.Mask" "B.Paste")
			(net "FM_USB_P0_EN_R_N")
		)
		(zone
			(layer "B.Cu")
			(hatch none 0.5)
			(connect_pads
				(clearance 0)
			)
			(min_thickness 0.25)
			(keepout
				(tracks not_allowed)
				(vias allowed)
				(pads allowed)
				(copperpour not_allowed)
				(footprints allowed)
			)
			(placement
				(enabled no)
				(sheetname "")
			)
			(fill
				(thermal_gap 0.5)
				(thermal_bridge_width 0.5)
				(island_removal_mode 0)
			)
			(polygon
				(pts
					(xy 468.63 -126.619) (xy 469.138 -126.619) (xy 469.138 -126.238) (xy 468.63 -126.238)
				)
			)
		)
		(zone
			(layer "B.Cu")
			(hatch none 0.5)
			(connect_pads
				(clearance 0)
			)
			(min_thickness 0.25)
			(keepout
				(tracks allowed)
				(vias not_allowed)
				(pads allowed)
				(copperpour not_allowed)
				(footprints allowed)
			)
			(placement
				(enabled no)
				(sheetname "")
			)
			(fill
				(thermal_gap 0.5)
				(thermal_bridge_width 0.5)
				(island_removal_mode 0)
			)
			(polygon
				(pts
					(xy 468.63 -126.238) (xy 469.138 -126.238) (xy 469.138 -126.619) (xy 468.63 -126.619)
				)
			)
		)
	)
	(footprint ""
		(layer "B.Cu")
		(at 94.26448 -140.04544 90)
		(property "Reference" "C5G115"
			(at -1.64973 0.78994 180)
			(unlocked yes)
			(layer "B.SilkS")
			(effects
				(font
					(size 0.7874 0.5842)
					(thickness 0.1524)
				)
				(justify mirror)
			)
		)
		(property "Value" ""
			(at 0 0 90)
			(layer "B.Fab")
			(effects
				(font
					(size 1.27 1.27)
				)
				(justify mirror)
			)
		)
		(duplicate_pad_numbers_are_jumpers no)
		(fp_rect
			(start -0.7239 -0.2159)
			(end 0.7239 1.9939)
			(stroke
				(width 0)
				(type default)
			)
			(fill no)
			(layer "B.CrtYd")
		)
		(fp_line
			(start 0.7239 -0.2159)
			(end 0.7239 1.9939)
			(stroke
				(width 0.1)
				(type default)
			)
			(layer "B.Fab")
		)
		(fp_line
			(start -0.7239 -0.2159)
			(end 0.7239 -0.2159)
			(stroke
				(width 0.1)
				(type default)
			)
			(layer "B.Fab")
		)
		(fp_line
			(start 0.7239 1.9939)
			(end -0.7239 1.9939)
			(stroke
				(width 0.1)
				(type default)
			)
			(layer "B.Fab")
		)
		(fp_line
			(start -0.7239 1.9939)
			(end -0.7239 -0.2159)
			(stroke
				(width 0.1)
				(type default)
			)
			(layer "B.Fab")
		)
		(pad "1" smd rect
			(at 0 0 270)
			(size 1.27 1.016)
			(layers "B.Cu" "B.Mask" "B.Paste")
			(net "PVDDQ_KLM")
		)
		(pad "2" smd rect
			(at 0 1.778 270)
			(size 1.27 1.016)
			(layers "B.Cu" "B.Mask" "B.Paste")
			(net "GND")
		)
		(zone
			(layer "B.Cu")
			(hatch none 0.5)
			(connect_pads
				(clearance 0)
			)
			(min_thickness 0.25)
			(keepout
				(tracks not_allowed)
				(vias allowed)
				(pads allowed)
				(copperpour not_allowed)
				(footprints allowed)
			)
			(placement
				(enabled no)
				(sheetname "")
			)
			(fill
				(thermal_gap 0.5)
				(thermal_bridge_width 0.5)
				(island_removal_mode 0)
			)
			(polygon
				(pts
					(xy 94.77248 -139.41044) (xy 95.53448 -139.41044) (xy 95.53448 -140.68044) (xy 94.77248 -140.68044)
				)
			)
		)
	)
	(footprint ""
		(layer "B.Cu")
		(at 475.484952 -14.0589 90)
		(property "Reference" "EU2T1"
			(at 1.40843 2.0574 0)
			(unlocked yes)
			(layer "B.SilkS")
			(effects
				(font
					(size 0.7874 0.5842)
					(thickness 0.1524)
				)
				(justify left mirror)
			)
		)
		(property "Value" ""
			(at 0 0 90)
			(layer "B.Fab")
			(effects
				(font
					(size 1.27 1.27)
				)
				(justify mirror)
			)
		)
		(duplicate_pad_numbers_are_jumpers no)
		(fp_circle
			(center 0.702056 -0.595376)
			(end 0.702056 -0.468376)
			(stroke
				(width 0.254)
				(type default)
			)
			(fill no)
			(layer "B.SilkS")
		)
		(fp_rect
			(start -1.4732 1.549908)
			(end -0.5842 -0.050292)
			(stroke
				(width 0)
				(type default)
			)
			(fill yes)
			(layer "B.Paste")
		)
		(fp_rect
			(start -2.078736 1.799844)
			(end 0.021336 -0.300228)
			(stroke
				(width 0)
				(type default)
			)
			(fill no)
			(layer "B.CrtYd")
		)
		(fp_line
			(start 0.021336 -0.300228)
			(end -2.078736 -0.300228)
			(stroke
				(width 0.1)
				(type default)
			)
			(layer "B.Fab")
		)
		(fp_line
			(start -2.078736 -0.300228)
			(end -2.078736 1.799844)
			(stroke
				(width 0.1)
				(type default)
			)
			(layer "B.Fab")
		)
		(fp_line
			(start 0.021336 1.799844)
			(end 0.021336 -0.300228)
			(stroke
				(width 0.1)
				(type default)
			)
			(layer "B.Fab")
		)
		(fp_line
			(start -2.078736 1.799844)
			(end 0.021336 1.799844)
			(stroke
				(width 0.1)
				(type default)
			)
			(layer "B.Fab")
		)
		(fp_circle
			(center 0.702056 -0.595376)
			(end 0.702056 -0.468376)
			(stroke
				(width 0.254)
				(type default)
			)
			(fill no)
			(layer "B.Fab")
		)
		(pad "1" smd rect
			(at 0 0 270)
			(size 0.6604 0.3048)
			(layers "B.Cu" "B.Mask" "B.Paste")
			(net "P5V_STBY")
		)
		(pad "2" smd rect
			(at 0 0.499872 270)
			(size 0.6604 0.3048)
			(layers "B.Cu" "B.Mask" "B.Paste")
			(net "FM_P3V3_CPLD_EN")
		)
		(pad "3" smd rect
			(at 0 0.999744 270)
			(size 0.6604 0.3048)
			(layers "B.Cu" "B.Mask" "B.Paste")
			(net "P5V_STBY")
		)
		(pad "4" smd rect
			(at 0 1.499616 270)
			(size 0.6604 0.3048)
			(layers "B.Cu" "B.Mask" "B.Paste")
			(net "GND")
		)
		(pad "5" smd rect
			(at -2.0574 1.499616 270)
			(size 0.6604 0.3048)
			(layers "B.Cu" "B.Mask" "B.Paste")
			(net "P3V3_STBY")
		)
		(pad "6" smd rect
			(at -2.0574 0.999744 270)
			(size 0.6604 0.3048)
			(layers "B.Cu" "B.Mask" "B.Paste")
			(net "P3V3")
		)
		(pad "7" smd rect
			(at -2.0574 0.499872 270)
			(size 0.6604 0.3048)
			(layers "B.Cu" "B.Mask" "B.Paste")
			(net "P3V3_SWITCH_G")
		)
		(pad "8" smd rect
			(at -2.0574 0 270)
			(size 0.6604 0.3048)
			(layers "B.Cu" "B.Mask" "B.Paste")
			(net "TP_SLG55021_P3V3_8")
		)
		(pad "9" smd rect
			(at -1.0287 0.749808 270)
			(size 0.889 1.6002)
			(layers "B.Cu" "B.Mask" "B.Paste")
			(net "GND")
		)
	)
	(footprint ""
		(layer "B.Cu")
		(at 20.7264 -31.6738 90)
		(property "Reference" "Q9T1"
			(at 1.37033 2.921 0)
			(unlocked yes)
			(layer "B.SilkS")
			(effects
				(font
					(size 0.7874 0.5842)
					(thickness 0.1524)
				)
				(justify left mirror)
			)
		)
		(property "Value" ""
			(at 0 0 90)
			(layer "B.Fab")
			(effects
				(font
					(size 1.27 1.27)
				)
				(justify mirror)
			)
		)
		(duplicate_pad_numbers_are_jumpers no)
		(fp_line
			(start -0.9525 -0.5715)
			(end -1.778 -0.5715)
			(stroke
				(width 0.1524)
				(type default)
			)
			(layer "B.SilkS")
		)
		(fp_line
			(start -1.778 -0.5715)
			(end -1.778 0.3175)
			(stroke
				(width 0.1524)
				(type default)
			)
			(layer "B.SilkS")
		)
		(fp_line
			(start -0.381 0.635)
			(end -0.381 1.27)
			(stroke
				(width 0.1524)
				(type default)
			)
			(layer "B.SilkS")
		)
		(fp_line
			(start -0.9525 2.4765)
			(end -1.778 2.4765)
			(stroke
				(width 0.1524)
				(type default)
			)
			(layer "B.SilkS")
		)
		(fp_line
			(start -1.778 2.4765)
			(end -1.778 1.5875)
			(stroke
				(width 0.1524)
				(type default)
			)
			(layer "B.SilkS")
		)
		(fp_circle
			(center 0.9525 -0.9271)
			(end 0.9525 -0.8001)
			(stroke
				(width 0.254)
				(type default)
			)
			(fill no)
			(layer "B.SilkS")
		)
		(fp_poly
			(pts
				(xy -1.778 2.4765) (xy -0.381 2.4765) (xy -0.381 -0.5715) (xy -1.778 -0.5715)
			)
			(stroke
				(width 0)
				(type default)
			)
			(fill no)
			(layer "B.CrtYd")
		)
		(fp_line
			(start -0.381 -0.5715)
			(end -0.381 2.4765)
			(stroke
				(width 0.1)
				(type default)
			)
			(layer "B.Fab")
		)
		(fp_line
			(start -1.778 -0.5715)
			(end -0.381 -0.5715)
			(stroke
				(width 0.1)
				(type default)
			)
			(layer "B.Fab")
		)
		(fp_line
			(start -0.381 2.4765)
			(end -1.778 2.4765)
			(stroke
				(width 0.1)
				(type default)
			)
			(layer "B.Fab")
		)
		(fp_line
			(start -1.778 2.4765)
			(end -1.778 -0.5715)
			(stroke
				(width 0.1)
				(type default)
			)
			(layer "B.Fab")
		)
		(fp_circle
			(center 0.9525 -0.9271)
			(end 0.9525 -0.8001)
			(stroke
				(width 0.254)
				(type default)
			)
			(fill no)
			(layer "B.Fab")
		)
		(pad "1" smd rect
			(at 0 0 270)
			(size 1.143 0.508)
			(layers "B.Cu" "B.Mask" "B.Paste")
			(net "FM_MATED_IN_D2_N")
		)
		(pad "2" smd rect
			(at 0 1.905 270)
			(size 1.143 0.508)
			(layers "B.Cu" "B.Mask" "B.Paste")
			(net "GND")
		)
		(pad "3" smd rect
			(at -2.159 0.9525 270)
			(size 1.143 0.508)
			(layers "B.Cu" "B.Mask" "B.Paste")
			(net "FM_P12V_HOTSWAP0_EN")
		)
	)
)
